# S9S_MB_2U (Grand Teton) — schematic netlist excerpt (pin names and nets, part order shuffled) for the footprints in the layout excerpt that follows; sources: Cadence DE-HDL packaged netlist, KiCad conversion of 03242023_DA0F0TMBIJ0_F0T_Motherboard_J_brd_V01_OCP.brd

PC430  Q_CAP  1UF 16V 10% X6S  pkg C0402  page 294 : A = SW_P12V_PVCCINFAON_CPU1_FLT ; B = GND
PC1252  Q_CAP  0.22UF 25V 10% X7R  pkg C0402  page 281 : A = SW_PVPP_HBM_CPU0_BST ; B = SW_PVPP_HBM_CPU0_SW
PJ47  Q_SHORT  EMPTY  pkg SM  page 266 : \1\ = VSENSE_PVCCIN_CPU0_DP ; \2\ = SH_PVCCIN_CPU0

(kicad_pcb
	(version 20260206)
	(generator "pcbnew")
	(generator_version "10.0")
	(general
		(thickness 1.6)
		(legacy_teardrops no)
	)
	(paper "A4")
	(title_block
		(title "03242023_DA0F0TMBIJ0_F0T_Motherboard_J_brd_V01_OCP.brd")
		(comment 1 "Grand Teton / footprints 584-586 of 6105")
	)
	(layers
		(0 "F.Cu" signal "TOP")
		(4 "In1.Cu" signal "GND")
		(6 "In2.Cu" signal "IN1")
		(8 "In3.Cu" signal "GND1")
		(10 "In4.Cu" signal "IN2")
		(12 "In5.Cu" signal "GND2")
		(14 "In6.Cu" signal "IN3")
		(16 "In7.Cu" signal "GND3")
		(18 "In8.Cu" signal "VCC")
		(20 "In9.Cu" signal "VCC1")
		(22 "In10.Cu" signal "GND4")
		(24 "In11.Cu" signal "IN4")
		(26 "In12.Cu" signal "GND5")
		(28 "In13.Cu" signal "IN5")
		(30 "In14.Cu" signal "GND6")
		(32 "In15.Cu" signal "IN6")
		(34 "In16.Cu" signal "GND7")
		(2 "B.Cu" signal "BOTTOM")
		(9 "F.Adhes" user "F.Adhesive")
		(11 "B.Adhes" user "B.Adhesive")
		(13 "F.Paste" user "Package Geometry/Pastemask Top")
		(15 "B.Paste" user "Package Geometry/Pastemask Bottom")
		(5 "F.SilkS" user "Ref Des/Silkscreen Top")
		(7 "B.SilkS" user "Ref Des/Silkscreen Bottom")
		(1 "F.Mask" user "Board Geometry/Soldermask Top")
		(3 "B.Mask" user "Board Geometry/Soldermask Bottom")
		(17 "Dwgs.User" user "User.Drawings")
		(19 "Cmts.User" user "User.Comments")
		(21 "Eco1.User" user "User.Eco1")
		(23 "Eco2.User" user "User.Eco2")
		(25 "Edge.Cuts" user "Board Geometry/Outline")
		(27 "Margin" user)
		(31 "F.CrtYd" user "Package Geometry/Place Bound Top")
		(29 "B.CrtYd" user "Package Geometry/Place Bound Bottom")
		(35 "F.Fab" user "Ref Des/Assembly Top")
		(33 "B.Fab" user "Ref Des/Assembly Bottom")
	)
	(footprint ""
		(layer "F.Cu")
		(at 48.581818 -178.060604 90)
		(property "Reference" "PC430"
			(at 0 0 90)
			(layer "F.SilkS")
			(hide yes)
			(effects
				(font
					(size 1.27 1.27)
				)
			)
		)
		(property "Value" ""
			(at 0 0 90)
			(layer "F.Fab")
			(effects
				(font
					(size 1.27 1.27)
				)
			)
		)
		(duplicate_pad_numbers_are_jumpers no)
		(fp_line
			(start 0.7874 -0.4064)
			(end 0.7874 0.4064)
			(stroke
				(width 0.1524)
				(type default)
			)
			(layer "F.SilkS")
		)
		(fp_line
			(start -0.7874 -0.4064)
			(end 0.7874 -0.4064)
			(stroke
				(width 0.1524)
				(type default)
			)
			(layer "F.SilkS")
		)
		(fp_line
			(start 0.7874 0.4064)
			(end -0.7874 0.4064)
			(stroke
				(width 0.1524)
				(type default)
			)
			(layer "F.SilkS")
		)
		(fp_line
			(start -0.7874 0.4064)
			(end -0.7874 -0.4064)
			(stroke
				(width 0.1524)
				(type default)
			)
			(layer "F.SilkS")
		)
		(fp_line
			(start -0.12065 -0.305054)
			(end -0.12065 -0.2794)
			(stroke
				(width 0.1)
				(type default)
			)
			(layer "F.Fab")
		)
		(fp_line
			(start -0.67945 -0.305054)
			(end -0.12065 -0.305054)
			(stroke
				(width 0.1)
				(type default)
			)
			(layer "F.Fab")
		)
		(fp_line
			(start 0.67945 -0.3048)
			(end 0.67945 0.3048)
			(stroke
				(width 0.1)
				(type default)
			)
			(layer "F.Fab")
		)
		(fp_line
			(start 0.12065 -0.3048)
			(end 0.67945 -0.3048)
			(stroke
				(width 0.1)
				(type default)
			)
			(layer "F.Fab")
		)
		(fp_line
			(start 0.12065 -0.2794)
			(end 0.12065 -0.3048)
			(stroke
				(width 0.1)
				(type default)
			)
			(layer "F.Fab")
		)
		(fp_line
			(start -0.12065 -0.2794)
			(end 0.12065 -0.2794)
			(stroke
				(width 0.1)
				(type default)
			)
			(layer "F.Fab")
		)
		(fp_line
			(start 0.120396 0.2794)
			(end -0.12065 0.2794)
			(stroke
				(width 0.1)
				(type default)
			)
			(layer "F.Fab")
		)
		(fp_line
			(start -0.12065 0.2794)
			(end -0.12065 0.3048)
			(stroke
				(width 0.1)
				(type default)
			)
			(layer "F.Fab")
		)
		(fp_line
			(start 0.67945 0.3048)
			(end 0.120396 0.3048)
			(stroke
				(width 0.1)
				(type default)
			)
			(layer "F.Fab")
		)
		(fp_line
			(start 0.120396 0.3048)
			(end 0.120396 0.2794)
			(stroke
				(width 0.1)
				(type default)
			)
			(layer "F.Fab")
		)
		(fp_line
			(start -0.12065 0.3048)
			(end -0.67945 0.3048)
			(stroke
				(width 0.1)
				(type default)
			)
			(layer "F.Fab")
		)
		(fp_line
			(start -0.67945 0.3048)
			(end -0.67945 -0.305054)
			(stroke
				(width 0.1)
				(type default)
			)
			(layer "F.Fab")
		)
		(pad "1" smd circle
			(at -0.40005 0 90)
			(size 0 0)
			(layers "F.Cu" "F.Mask" "F.Paste")
			(net "SW_P12V_PVCCINFAON_CPU1_FLT")
		)
		(pad "2" smd circle
			(at 0.40005 0 90)
			(size 0 0)
			(layers "F.Cu" "F.Mask" "F.Paste")
			(net "GND")
		)
	)
	(footprint ""
		(layer "F.Cu")
		(at 371.297962 -361.570778 90)
		(property "Reference" "PC1252"
			(at 0 0 90)
			(layer "F.SilkS")
			(hide yes)
			(effects
				(font
					(size 1.27 1.27)
				)
			)
		)
		(property "Value" ""
			(at 0 0 90)
			(layer "F.Fab")
			(effects
				(font
					(size 1.27 1.27)
				)
			)
		)
		(duplicate_pad_numbers_are_jumpers no)
		(fp_line
			(start 0.7874 -0.4064)
			(end 0.7874 0.4064)
			(stroke
				(width 0.1524)
				(type default)
			)
			(layer "F.SilkS")
		)
		(fp_line
			(start -0.7874 -0.4064)
			(end 0.7874 -0.4064)
			(stroke
				(width 0.1524)
				(type default)
			)
			(layer "F.SilkS")
		)
		(fp_line
			(start 0.7874 0.4064)
			(end -0.7874 0.4064)
			(stroke
				(width 0.1524)
				(type default)
			)
			(layer "F.SilkS")
		)
		(fp_line
			(start -0.7874 0.4064)
			(end -0.7874 -0.4064)
			(stroke
				(width 0.1524)
				(type default)
			)
			(layer "F.SilkS")
		)
		(fp_line
			(start -0.12065 -0.305054)
			(end -0.12065 -0.2794)
			(stroke
				(width 0.1)
				(type default)
			)
			(layer "F.Fab")
		)
		(fp_line
			(start -0.67945 -0.305054)
			(end -0.12065 -0.305054)
			(stroke
				(width 0.1)
				(type default)
			)
			(layer "F.Fab")
		)
		(fp_line
			(start 0.67945 -0.3048)
			(end 0.67945 0.3048)
			(stroke
				(width 0.1)
				(type default)
			)
			(layer "F.Fab")
		)
		(fp_line
			(start 0.12065 -0.3048)
			(end 0.67945 -0.3048)
			(stroke
				(width 0.1)
				(type default)
			)
			(layer "F.Fab")
		)
		(fp_line
			(start 0.12065 -0.2794)
			(end 0.12065 -0.3048)
			(stroke
				(width 0.1)
				(type default)
			)
			(layer "F.Fab")
		)
		(fp_line
			(start -0.12065 -0.2794)
			(end 0.12065 -0.2794)
			(stroke
				(width 0.1)
				(type default)
			)
			(layer "F.Fab")
		)
		(fp_line
			(start 0.120396 0.2794)
			(end -0.12065 0.2794)
			(stroke
				(width 0.1)
				(type default)
			)
			(layer "F.Fab")
		)
		(fp_line
			(start -0.12065 0.2794)
			(end -0.12065 0.3048)
			(stroke
				(width 0.1)
				(type default)
			)
			(layer "F.Fab")
		)
		(fp_line
			(start 0.67945 0.3048)
			(end 0.120396 0.3048)
			(stroke
				(width 0.1)
				(type default)
			)
			(layer "F.Fab")
		)
		(fp_line
			(start 0.120396 0.3048)
			(end 0.120396 0.2794)
			(stroke
				(width 0.1)
				(type default)
			)
			(layer "F.Fab")
		)
		(fp_line
			(start -0.12065 0.3048)
			(end -0.67945 0.3048)
			(stroke
				(width 0.1)
				(type default)
			)
			(layer "F.Fab")
		)
		(fp_line
			(start -0.67945 0.3048)
			(end -0.67945 -0.305054)
			(stroke
				(width 0.1)
				(type default)
			)
			(layer "F.Fab")
		)
		(pad "1" smd circle
			(at -0.40005 0 90)
			(size 0 0)
			(layers "F.Cu" "F.Mask" "F.Paste")
			(net "SW_PVPP_HBM_CPU0_BST")
		)
		(pad "2" smd circle
			(at 0.40005 0 90)
			(size 0 0)
			(layers "F.Cu" "F.Mask" "F.Paste")
			(net "SW_PVPP_HBM_CPU0_SW")
		)
	)
	(footprint ""
		(layer "F.Cu")
		(at 350.75876 -352.02114 180)
		(property "Reference" "PJ47"
			(at 2.338324 -1.363472 0)
			(unlocked yes)
			(layer "F.SilkS")
			(effects
				(font
					(size 0.7874 0.5842)
					(thickness 0.1524)
				)
				(justify left)
			)
		)
		(property "Value" ""
			(at 0 0 180)
			(layer "F.Fab")
			(effects
				(font
					(size 1.27 1.27)
				)
			)
		)
		(duplicate_pad_numbers_are_jumpers no)
		(pad "1" smd circle
			(at -0.7493 0 270)
			(size 0 0)
			(layers "F.Cu" "F.Mask" "F.Paste")
			(net "VSENSE_PVCCIN_CPU0_DP")
		)
		(pad "2" smd rect
			(at 0.7493 0 90)
			(size 0.7112 0.8128)
			(layers "F.Cu" "F.Mask" "F.Paste")
			(net "SH_PVCCIN_CPU0")
		)
		(zone
			(layer "F.Cu")
			(hatch none 0.5)
			(connect_pads
				(clearance 0)
			)
			(min_thickness 0.25)
			(keepout
				(tracks allowed)
				(vias not_allowed)
				(pads allowed)
				(copperpour not_allowed)
				(footprints allowed)
			)
			(placement
				(enabled no)
				(sheetname "")
			)
			(fill
				(thermal_gap 0.5)
				(thermal_bridge_width 0.5)
				(island_removal_mode 0)
			)
			(polygon
				(pts
					(xy 349.55226 -351.61474) (xy 351.93986 -351.61474) (xy 351.93986 -352.432366) (xy 349.55226 -352.432366)
				)
			)
		)
	)
)
